# S9S_MB_2U (Grand Teton) — schematic netlist excerpt (pin names and nets, part order shuffled) for the footprints in the layout excerpt that follows; sources: Cadence DE-HDL packaged netlist, KiCad conversion of 03242023_DA0F0TMBIJ0_F0T_Motherboard_J_brd_V01_OCP.brd

J5  SCONN288_ADR50017P130CC  SCONN288_ADR50017-P130CC IO  pkg DDR288S_1-1VXB  page 86
  VIN_BULK0  = P12V_S3_AUX_CPU0_NVDIMM
  RFU0  = TP_CHC_CPU0_DIMM1_FRU_0
  VIN_MGMT  = P3V3_AUX
  HSCL  = I3C_SPD_DDRABCD_CPU0_LVC1_SCL_4
  HSDA  = I3C_SPD_DDRABCD_CPU0_LVC1_SDA
  VSS0  = GND
  DQ0_A  = M_C_CPU0_SA_DQ<0>
  VSS1  = GND
  DQ1_A  = M_C_CPU0_SA_DQ<1>
  VSS2  = GND
  DQS0_A_T  = M_C_CPU0_SA_DQS_DP<0>
  DQS0_A_C  = M_C_CPU0_SA_DQS_DN<0>
  VSS3  = GND
  DQ4_A  = M_C_CPU0_SA_DQ<4>
  VSS4  = GND
  DQ5_A  = M_C_CPU0_SA_DQ<5>
  VSS5  = GND
  DQ8_A  = M_C_CPU0_SA_DQ<8>
  VSS6  = GND
  DQ9_A  = M_C_CPU0_SA_DQ<9>
  VSS7  = GND
  DQS1_A_T  = M_C_CPU0_SA_DQS_DP<1>
  DQS1_A_C  = M_C_CPU0_SA_DQS_DN<1>
  VSS8  = GND
  DQ12_A  = M_C_CPU0_SA_DQ<12>
  VSS9  = GND
  DQ13_A  = M_C_CPU0_SA_DQ<13>
  VSS10  = GND
  DQ16_A  = M_C_CPU0_SA_DQ<16>
  VSS11  = GND
  DQ17_A  = M_C_CPU0_SA_DQ<17>
  VSS12  = GND
  DQS2_A_T  = M_C_CPU0_SA_DQS_DP<2>
  DQS2_A_C  = M_C_CPU0_SA_DQS_DN<2>
  VSS13  = GND
  DQ20_A  = M_C_CPU0_SA_DQ<20>
  VSS14  = GND
  DQ21_A  = M_C_CPU0_SA_DQ<21>
  VSS15  = GND
  DQ24_A  = M_C_CPU0_SA_DQ<24>
  VSS16  = GND
  DQ25_A  = M_C_CPU0_SA_DQ<25>
  VSS17  = GND
  DQS3_A_T  = M_C_CPU0_SA_DQS_DP<3>
  DQS3_A_C  = M_C_CPU0_SA_DQS_DN<3>
  VSS18  = GND
  DQ28_A  = M_C_CPU0_SA_DQ<28>
  VSS19  = GND
  DQ29_A  = M_C_CPU0_SA_DQ<29>
  VSS20  = GND
  CB0_A  = M_C_CPU0_SA_CB<0>
  VSS21  = GND
  CB1_A  = M_C_CPU0_SA_CB<1>
  VSS22  = GND
  DQS4_A_T  = M_C_CPU0_SA_DQS_DP<4>
  DQS4_A_C  = M_C_CPU0_SA_DQS_DN<4>
  VSS23  = GND
  CB4_A  = M_C_CPU0_SA_CB<4>
  VSS24  = GND
  CB5_A  = M_C_CPU0_SA_CB<5>
  VSS25  = GND
  ALERT_N  = M_C_CPU0_ALERT_N
  VSS26  = GND
  CS0_A_N  = M_C_CPU0_SA_CS_N<0>
  VSS27  = GND
  CA0_A  = M_C_CPU0_SA_CA<0>
  VSS28  = GND
  CA2_A  = M_C_CPU0_SA_CA<2>
  VSS29  = GND
  CA4_A  = M_C_CPU0_SA_CA<4>
  VSS30  = GND
  CA6_A  = M_C_CPU0_SA_CA<6>
  VSS31  = GND
  PAR_A  = M_C_CPU0_SA_PAR
  VSS32  = GND
  CA0_B  = M_C_CPU0_SB_CA<0>
  VSS33  = GND
  CA2_B  = M_C_CPU0_SB_CA<2>
  VSS34  = GND
  CA4_B  = M_C_CPU0_SB_CA<4>
  VSS35  = GND
  CA6_B  = M_C_CPU0_SB_CA<6>
  VSS36  = GND
  CS0_B_N  = M_C_CPU0_SB_CS_N<0>
  VSS37  = GND
  \lbd||rsp_a_n\  = M_C_CPU0_SA_RSP<0>
  \lbs||rsp_b_n\  = M_C_CPU0_SB_RSP<0>
  VSS38  = GND
  CB4_B  = M_C_CPU0_SB_CB<4>
  VSS39  = GND
  CB5_B  = M_C_CPU0_SB_CB<5>
  VSS40  = GND
  \dqs9_b_t||tdqs9_b_t||dbi4_b_n\  = M_C_CPU0_SB_DQS_DP<9>
  \dqs9_b_c||tdqs9_b_c\  = M_C_CPU0_SB_DQS_DN<9>
  VSS41  = GND
  CB0_B  = M_C_CPU0_SB_CB<0>
  VSS42  = GND
  CB1_B  = M_C_CPU0_SB_CB<1>
  VSS43  = GND
  DQ0_B  = M_C_CPU0_SB_DQ<0>
  VSS44  = GND
  DQ1_B  = M_C_CPU0_SB_DQ<1>
  VSS45  = GND
  DQS0_B_T  = M_C_CPU0_SB_DQS_DP<0>
  DQS0_B_C  = M_C_CPU0_SB_DQS_DN<0>
  VSS46  = GND
  DQ4_B  = M_C_CPU0_SB_DQ<4>
  VSS47  = GND
  DQ5_B  = M_C_CPU0_SB_DQ<5>
  VSS48  = GND
  DQ8_B  = M_C_CPU0_SB_DQ<8>
  VSS49  = GND
  DQ9_B  = M_C_CPU0_SB_DQ<9>
  VSS50  = GND
  DQS1_B_T  = M_C_CPU0_SB_DQS_DP<1>
  DQS1_B_C  = M_C_CPU0_SB_DQS_DN<1>
  VSS51  = GND
  DQ12_B  = M_C_CPU0_SB_DQ<12>
  VSS52  = GND
  DQ13_B  = M_C_CPU0_SB_DQ<13>
  VSS53  = GND
  DQ16_B  = M_C_CPU0_SB_DQ<16>
  VSS54  = GND
  DQ17_B  = M_C_CPU0_SB_DQ<17>
  VSS55  = GND
  DQS2_B_T  = M_C_CPU0_SB_DQS_DP<2>
  DQS2_B_C  = M_C_CPU0_SB_DQS_DN<2>
  VSS56  = GND
  DQ20_B  = M_C_CPU0_SB_DQ<20>
  VSS57  = GND
  DQ21_B  = M_C_CPU0_SB_DQ<21>
  VSS58  = GND
  DQ24_B  = M_C_CPU0_SB_DQ<24>
  VSS59  = GND
  DQ25_B  = M_C_CPU0_SB_DQ<25>
  VSS60  = GND
  DQS3_B_T  = M_C_CPU0_SB_DQS_DP<3>
  DQS3_B_C  = M_C_CPU0_SB_DQS_DN<3>
  VSS61  = GND
  DQ28_B  = M_C_CPU0_SB_DQ<28>
  VSS62  = GND
  DQ29_B  = M_C_CPU0_SB_DQ<29>
  VSS63  = GND
  RFU1  = TP_CHC_CPU0_DIMM1_FRU_1
  VIN_BULK1  = P12V_S3_AUX_CPU0_NVDIMM
  VIN_BULK2  = P12V_S3_AUX_CPU0_NVDIMM
  \pwr_good||fail_n\  = PWRGD_CHC_CPU0_DIMM1
  HSA  = PD_CHC_CPU0_DIMM1_SAA
  RFU2  = TP_CHC_CPU0_DIMM1_FRU_2
  RFU3  = TP_CHC_CPU0_DIMM1_FRU_3
  VSS64  = GND
  DQ2_A  = M_C_CPU0_SA_DQ<2>
  VSS65  = GND
  DQ3_A  = M_C_CPU0_SA_DQ<3>
  VSS66  = GND
  \dqs5_a_c||tdqs5_a_c||dqs5_a_t||tdqs5_a_t\  = M_C_CPU0_SA_DQS_DN<5>
  \dqs5_a_t||tdqs5_a_t\  = M_C_CPU0_SA_DQS_DP<5>
  VSS67  = GND
  DQ6_A  = M_C_CPU0_SA_DQ<6>
  VSS68  = GND
  DQ7_A  = M_C_CPU0_SA_DQ<7>
  VSS69  = GND
  DQ10_A  = M_C_CPU0_SA_DQ<10>
  VSS70  = GND
  DQ11_A  = M_C_CPU0_SA_DQ<11>
  VSS71  = GND
  \dqs6_a_c||tdqs6_a_c||dqs6_a_t||tdqs6_a_t\  = M_C_CPU0_SA_DQS_DN<6>
  \dqs6_a_t||tdqs6_a_t\  = M_C_CPU0_SA_DQS_DP<6>
  VSS72  = GND
  DQ14_A  = M_C_CPU0_SA_DQ<14>
  VSS73  = GND
  DQ15_A  = M_C_CPU0_SA_DQ<15>
  VSS74  = GND
  DQ18_A  = M_C_CPU0_SA_DQ<18>
  VSS75  = GND
  DQ19_A  = M_C_CPU0_SA_DQ<19>
  VSS76  = GND
  \dqs7_a_c||tdqs7_a_c\  = M_C_CPU0_SA_DQS_DN<7>
  \dqs7_a_t||tdqs7_a_t\  = M_C_CPU0_SA_DQS_DP<7>
  VSS77  = GND
  DQ22_A  = M_C_CPU0_SA_DQ<22>
  VSS78  = GND
  DQ23_A  = M_C_CPU0_SA_DQ<23>
  VSS79  = GND
  DQ26_A  = M_C_CPU0_SA_DQ<26>
  VSS80  = GND
  DQ27_A  = M_C_CPU0_SA_DQ<27>
  VSS81  = GND
  \dqs8_a_c||tdqs8_a_c\  = M_C_CPU0_SA_DQS_DN<8>
  \dqs8_a_t||tdqs8_a_t\  = M_C_CPU0_SA_DQS_DP<8>
  VSS82  = GND
  DQ30_A  = M_C_CPU0_SA_DQ<30>
  VSS83  = GND
  DQ31_A  = M_C_CPU0_SA_DQ<31>
  VSS84  = GND
  CB2_A  = M_C_CPU0_SA_CB<2>
  VSS85  = GND
  CB3_A  = M_C_CPU0_SA_CB<3>
  VSS86  = GND
  \dqs9_a_c||tdqs9_a_c\  = M_C_CPU0_SA_DQS_DN<9>
  \dqs9_a_t||tdqs9_a_t\  = M_C_CPU0_SA_DQS_DP<9>
  VSS87  = GND
  CB6_A  = M_C_CPU0_SA_CB<6>
  VSS88  = GND
  CB7_A  = M_C_CPU0_SA_CB<7>
  VSS89  = GND
  RESET_N  = RST_M_CD_CPU0_FPGA_N
  VSS90  = GND
  CS1_A_N  = M_C_CPU0_SA_CS_N<1>
  VSS91  = GND
  CA1_A  = M_C_CPU0_SA_CA<1>
  VSS92  = GND
  CA3_A  = M_C_CPU0_SA_CA<3>
  VSS93  = GND
  CA5_A  = M_C_CPU0_SA_CA<5>
  VSS94  = GND
  CK_T  = M_C_CPU0_CLK_DP<0>
  CK_C  = M_C_CPU0_CLK_DN<0>
  VSS95  = GND
  RFU4  = TP_CHC_CPU0_DIMM1_FRU_4
  CA1_B  = M_C_CPU0_SB_CA<1>
  VSS96  = GND
  CA3_B  = M_C_CPU0_SB_CA<3>
  VSS97  = GND
  CA5_B  = M_C_CPU0_SB_CA<5>
  VSS98  = GND
  PAR_B  = M_C_CPU0_SB_PAR
  VSS99  = GND
  CS1_B_N  = M_C_CPU0_SB_CS_N<1>
  VSS100  = GND
  RFU5  = TP_CHC_CPU0_DIMM1_FRU_5
  RFU6  = TP_CHC_CPU0_DIMM1_FRU_6
  VSS101  = GND
  CB6_B  = M_C_CPU0_SB_CB<6>
  VSS102  = GND
  CB7_B  = M_C_CPU0_SB_CB<7>
  VSS103  = GND
  DQS4_B_C  = M_C_CPU0_SB_DQS_DN<4>
  DQS4_B_T  = M_C_CPU0_SB_DQS_DP<4>
  VSS104  = GND
  CB2_B  = M_C_CPU0_SB_CB<2>
  VSS105  = GND
  CB3_B  = M_C_CPU0_SB_CB<3>
  VSS106  = GND
  DQ2_B  = M_C_CPU0_SB_DQ<2>
  VSS107  = GND
  DQ3_B  = M_C_CPU0_SB_DQ<3>
  VSS108  = GND
  \dqs5_b_c||tdqs5_b_c\  = M_C_CPU0_SB_DQS_DN<5>
  \dqs5_b_t||tdqs5_b_t\  = M_C_CPU0_SB_DQS_DP<5>
  VSS109  = GND
  DQ6_B  = M_C_CPU0_SB_DQ<6>
  VSS110  = GND
  DQ7_B  = M_C_CPU0_SB_DQ<7>
  VSS111  = GND
  DQ10_B  = M_C_CPU0_SB_DQ<10>
  VSS112  = GND
  DQ11_B  = M_C_CPU0_SB_DQ<11>
  VSS113  = GND
  \dqs6_b_c||tdqs6_b_c\  = M_C_CPU0_SB_DQS_DN<6>
  \dqs6_b_t||tdqs6_b_t\  = M_C_CPU0_SB_DQS_DP<6>
  VSS114  = GND
  DQ14_B  = M_C_CPU0_SB_DQ<14>
  VSS115  = GND
  DQ15_B  = M_C_CPU0_SB_DQ<15>
  VSS116  = GND
  DQ18_B  = M_C_CPU0_SB_DQ<18>
  VSS117  = GND
  DQ19_B  = M_C_CPU0_SB_DQ<19>
  VSS118  = GND
  \dqs7_b_c||tdqs7_b_c\  = M_C_CPU0_SB_DQS_DN<7>
  \dqs7_b_t||tdqs7_b_t\  = M_C_CPU0_SB_DQS_DP<7>
  VSS119  = GND
  DQ22_B  = M_C_CPU0_SB_DQ<22>
  VSS120  = GND
  DQ23_B  = M_C_CPU0_SB_DQ<23>
  VSS121  = GND
  DQ26_B  = M_C_CPU0_SB_DQ<26>
  VSS122  = GND
  DQ27_B  = M_C_CPU0_SB_DQ<27>
  VSS123  = GND
  \dqs8_b_c||tdqs8_b_c\  = M_C_CPU0_SB_DQS_DN<8>
  \dqs8_b_t||tdqs8_b_t\  = M_C_CPU0_SB_DQS_DP<8>
  VSS124  = GND
  DQ30_B  = M_C_CPU0_SB_DQ<30>
  VSS125  = GND
  DQ31_B  = M_C_CPU0_SB_DQ<31>
  VSS126  = GND
  G1  = GND
  G2  = GND
  G3  = GND

(kicad_pcb
	(version 20260206)
	(generator "pcbnew")
	(generator_version "10.0")
	(general
		(thickness 1.6)
		(legacy_teardrops no)
	)
	(paper "A4")
	(title_block
		(title "03242023_DA0F0TMBIJ0_F0T_Motherboard_J_brd_V01_OCP.brd")
		(comment 1 "Grand Teton / footprint 885 of 6105 (J5), pads 275-291 of 291")
	)
	(layers
		(0 "F.Cu" signal "TOP")
		(4 "In1.Cu" signal "GND")
		(6 "In2.Cu" signal "IN1")
		(8 "In3.Cu" signal "GND1")
		(10 "In4.Cu" signal "IN2")
		(12 "In5.Cu" signal "GND2")
		(14 "In6.Cu" signal "IN3")
		(16 "In7.Cu" signal "GND3")
		(18 "In8.Cu" signal "VCC")
		(20 "In9.Cu" signal "VCC1")
		(22 "In10.Cu" signal "GND4")
		(24 "In11.Cu" signal "IN4")
		(26 "In12.Cu" signal "GND5")
		(28 "In13.Cu" signal "IN5")
		(30 "In14.Cu" signal "GND6")
		(32 "In15.Cu" signal "IN6")
		(34 "In16.Cu" signal "GND7")
		(2 "B.Cu" signal "BOTTOM")
		(9 "F.Adhes" user "F.Adhesive")
		(11 "B.Adhes" user "B.Adhesive")
		(13 "F.Paste" user "Package Geometry/Pastemask Top")
		(15 "B.Paste" user "Package Geometry/Pastemask Bottom")
		(5 "F.SilkS" user "Ref Des/Silkscreen Top")
		(7 "B.SilkS" user "Ref Des/Silkscreen Bottom")
		(1 "F.Mask" user "Board Geometry/Soldermask Top")
		(3 "B.Mask" user "Board Geometry/Soldermask Bottom")
		(17 "Dwgs.User" user "User.Drawings")
		(19 "Cmts.User" user "User.Comments")
		(21 "Eco1.User" user "User.Eco1")
		(23 "Eco2.User" user "User.Eco2")
		(25 "Edge.Cuts" user "Board Geometry/Outline")
		(27 "Margin" user)
		(31 "F.CrtYd" user "Package Geometry/Place Bound Top")
		(29 "B.CrtYd" user "Package Geometry/Place Bound Bottom")
		(35 "F.Fab" user "Ref Des/Assembly Top")
		(33 "B.Fab" user "Ref Des/Assembly Bottom")
	)
	(footprint ""
		(layer "F.Cu")
		(at 273.218148 -258.091686)
		(property "Reference" "J5"
			(at -3.683 -81.702148 0)
			(unlocked yes)
			(layer "F.SilkS")
			(effects
				(font
					(size 0.7874 0.5842)
					(thickness 0.1524)
				)
				(justify left)
			)
		)
		(property "Value" ""
			(at 0 0 0)
			(layer "F.Fab")
			(effects
				(font
					(size 1.27 1.27)
				)
			)
		)
		(duplicate_pad_numbers_are_jumpers no)
		(pad "275" smd rect
			(at 2.050034 52.274978 270)
			(size 0.519938 1.4986)
			(layers "F.Cu" "F.Mask" "F.Paste")
			(net "GND")
		)
		(pad "276" smd rect
			(at 2.050034 53.125116 270)
			(size 0.519938 1.4986)
			(layers "F.Cu" "F.Mask" "F.Paste")
			(net "M_C_CPU0_SB_DQ<23>")
		)
		(pad "277" smd rect
			(at 2.050034 53.975 270)
			(size 0.519938 1.4986)
			(layers "F.Cu" "F.Mask" "F.Paste")
			(net "GND")
		)
		(pad "278" smd rect
			(at 2.050034 54.824884 270)
			(size 0.519938 1.4986)
			(layers "F.Cu" "F.Mask" "F.Paste")
			(net "M_C_CPU0_SB_DQ<26>")
		)
		(pad "279" smd rect
			(at 2.050034 55.675022 270)
			(size 0.519938 1.4986)
			(layers "F.Cu" "F.Mask" "F.Paste")
			(net "GND")
		)
		(pad "280" smd rect
			(at 2.050034 56.524906 270)
			(size 0.519938 1.4986)
			(layers "F.Cu" "F.Mask" "F.Paste")
			(net "M_C_CPU0_SB_DQ<27>")
		)
		(pad "281" smd rect
			(at 2.050034 57.375044 270)
			(size 0.519938 1.4986)
			(layers "F.Cu" "F.Mask" "F.Paste")
			(net "GND")
		)
		(pad "282" smd rect
			(at 2.050034 58.224928 270)
			(size 0.519938 1.4986)
			(layers "F.Cu" "F.Mask" "F.Paste")
			(net "M_C_CPU0_SB_DQS_DN<8>")
		)
		(pad "283" smd rect
			(at 2.050034 59.075066 270)
			(size 0.519938 1.4986)
			(layers "F.Cu" "F.Mask" "F.Paste")
			(net "M_C_CPU0_SB_DQS_DP<8>")
		)
		(pad "284" smd rect
			(at 2.050034 59.92495 270)
			(size 0.519938 1.4986)
			(layers "F.Cu" "F.Mask" "F.Paste")
			(net "GND")
		)
		(pad "285" smd rect
			(at 2.050034 60.775088 270)
			(size 0.519938 1.4986)
			(layers "F.Cu" "F.Mask" "F.Paste")
			(net "M_C_CPU0_SB_DQ<30>")
		)
		(pad "286" smd rect
			(at 2.050034 61.624972 270)
			(size 0.519938 1.4986)
			(layers "F.Cu" "F.Mask" "F.Paste")
			(net "GND")
		)
		(pad "287" smd rect
			(at 2.050034 62.47511 270)
			(size 0.519938 1.4986)
			(layers "F.Cu" "F.Mask" "F.Paste")
			(net "M_C_CPU0_SB_DQ<31>")
		)
		(pad "288" smd rect
			(at 2.050034 63.324994 270)
			(size 0.519938 1.4986)
			(layers "F.Cu" "F.Mask" "F.Paste")
			(net "GND")
		)
		(pad "G1" thru_hole oval
			(at 0 -68.97497)
			(size 2.8194 1.5748)
			(drill oval 2.4384 1.1938)
			(layers "*.Cu" "*.Mask")
			(remove_unused_layers no)
			(net "GND")
			(clearance 0.127)
			(thermal_gap 0.127)
		)
		(pad "G2" thru_hole oval
			(at 0 3.875024)
			(size 2.8194 1.5748)
			(drill oval 2.4384 1.1938)
			(layers "*.Cu" "*.Mask")
			(remove_unused_layers no)
			(net "GND")
			(clearance 0.127)
			(thermal_gap 0.127)
		)
		(pad "G3" thru_hole oval
			(at 0 68.97497)
			(size 2.8194 1.5748)
			(drill oval 2.4384 1.1938)
			(layers "*.Cu" "*.Mask")
			(remove_unused_layers no)
			(net "GND")
			(clearance 0.127)
			(thermal_gap 0.127)
		)
	)
)
